FILE_TYPE = CONNECTIVITY;
{Allegro Design Entry HDL 17.4-2019 S026 (4007227) 1/17/2022}
"PAGE_NUMBER" = 350;
0"NC";
1"GND\g";
2"P3V3_AUX\g";
3"P3V3_AUX\g";
4"GND\g";
5"GND\g";
6"P12V_AUX\g";
7"GND\g";
8"GND\g";
9"GND\g";
10"P3V3_AUX\g";
11"P3V3_AUX\g";
12"GND\g";
13"GND\g";
14"GND\g";
15"GND\g";
16"GND\g";
17"GND\g";
18"P12V_SCM_EN";
19"P12V_SCM_R\g";
20"P12V_AUX\g";
21"P12V_SCM_AVIN_PD";
22"P12V_SCM_OV_FB";
23"HP_LVC3_SCM_HSC_PWRGD_R";
24"P12V_SCM_FLTB_N";
25"P12V_SCM_IMON";
26"P12V_SCM_EN_R2";
27"GND\g";
28"P12V_SCM_TIMER";
29"P12V_SCM_ISET";
30"P12V_SCM_SS";
31"GND\g";
32"GND\g";
33"P12V_SCM_OV";
34"GND\g";
35"P12V_AUX\g";
36"P12V_SCM_AVIN_PD";
37"P12V_SCM_R\g";
38"GND\g";
39"P3V3_AUX\g";
40"GND\g";
41"GND\g";
42"P12V_AUX\g";
43"GND\g";
44"HP_LVC3_SCM_HSC_PWRGD";
45"HP_LVC3_SCM_HSC_PWRGD";
46"P12V_SCM_ISET_R";
47"FM_SCM_PRSNT1_R_N";
48"P12V_SCM_EN_R";
49"P12V_SCM_EN_G";
50"P12V_SCM_UV";
51"P12V_SCM_REG";
52"P12V_SCM_PWRGD";
53"P12V_SCM_GATE";
54"P12V_SCM_FAULT_N";
55"P12V_SCM_UV_R";
56"P12V_SCM_VCC";
57"P12V_SCM_CB";
58"P12V_SCM_FAULT_R_N";
59"P12V_SCM_SENSE";
60"VIRTUAL_RESEAT_FPGA_N";
61"P12V_SCM_FAULT_R_N";
62"FM_SCM_PRSNT1_N";
%"UNIVERSAL_GND"
"1","(-750,12850)","0","pure_quanta_power","I10";
;
CDS_LIB"pure_quanta_power"
HDL_POWER"GND";
"A"1;
%"Q_RES"
"2","(-75,11575)","0","pure_quanta","I11";
;
LOCATION"PR3999"
$SEC"1"
CDS_SEC"1"
VALUE"24.3K"
TOLERANCE"1%"
ROOM"SCM_P12V_MPS_BOM2"
WATTAGE"1/16W"
MATERIAL"CHIP"
PACK_TYPE"0402LF"
CDS_LIB"pure_quanta"
PART_NUMBER"CS32432FB03";
"A"
$PN"1"29;
"B"
$PN"2"12;
%"Q_RES"
"2","(350,11550)","0","pure_quanta","I12";
;
LOCATION"PR4540"
$SEC"1"
CDS_SEC"1"
WATTAGE"1/16W"
MATERIAL"CHIP"
ROOM"SCM_P12V_MPS_BOM2"
VALUE"20K"
TOLERANCE"1%"
PACK_TYPE"0402LF"
CDS_LIB"pure_quanta"
PART_NUMBER"CS32002FB06";
"A"
$PN"1"29;
"B"
$PN"2"46;
%"GND"
"1","(425,11900)","0","pure_quanta_power","I13";
;
CDS_LIB"pure_quanta_power"
SIZE"1B"
HDL_POWER"GND";
"A<SIZE-1..0>\NAC"27;
%"Q_RES"
"1","(300,12150)","0","pure_quanta","I14";
;
LOCATION"R3998"
$SEC"1"
CDS_SEC"1"
PACK_TYPE"0402LF"
TOLERANCE"5%"
VALUE"0"
WATTAGE"1/16W"
ROOM"SCM_P12V_MPS_BOM2"
MATERIAL"CHIP"
CDS_LIB"pure_quanta"
PART_NUMBER"CS00002JB13";
"B"
$PN"2"26;
"A"
$PN"1"18;
%"UNIVERSAL_POWER"
"1","(-2750,13625)","0","pure_quanta_power","I16";
;
HDL_POWER"P3V3_AUX"
CDS_LIB"pure_quanta_power";
"A"2;
%"Q_RES"
"1","(-2825,14275)","0","pure_quanta","I17";
;
LOCATION"R3996"
$SEC"1"
CDS_SEC"1"
VALUE"0"
TOLERANCE"5%"
WATTAGE"1/16W"
MATERIAL"CHIP"
PACK_TYPE"0402LF"
CDS_LIB"pure_quanta"
PART_NUMBER"CS00002JB13";
"B"
$PN"2"18;
"A"
$PN"1"60;
%"Q_RES"
"2","(-2525,14550)","0","pure_quanta","I18";
;
LOCATION"R1857"
$SEC"1"
CDS_SEC"1"
VALUE"10K"
WATTAGE"1/16W"
MATERIAL"CHIP"
TOLERANCE"1%"
PACK_TYPE"0402LF"
CDS_LIB"pure_quanta"
PART_NUMBER"CS31002FB08";
"A"
$PN"1"3;
"B"
$PN"2"18;
%"UNIVERSAL_POWER"
"1","(-2525,14800)","0","pure_quanta_power","I19";
;
HDL_POWER"P3V3_AUX"
CDS_LIB"pure_quanta_power";
"A"3;
%"Q_RES"
"2","(-2750,13400)","2","pure_quanta","I2";
;
LOCATION"R1854"
$SEC"1"
CDS_SEC"1"
VALUE"1K"
WATTAGE"1/16W"
TOLERANCE"1%"
MATERIAL"CHIP"
PACK_TYPE"0402LF"
CDS_LIB"pure_quanta"
PART_NUMBER"CS21002FB06";
"A"
$PN"1"2;
"B"
$PN"2"62;
%"Q_RES"
"1","(-2025,14275)","0","pure_quanta","I20";
;
LOCATION"R4062"
$SEC"1"
CDS_SEC"1"
PACK_TYPE"0402LF"
WATTAGE"1/16W"
TOLERANCE"5%"
MATERIAL"CHIP"
VALUE"0"
ROOM"SCM_P12V_MAM_BOM1"
CDS_LIB"pure_quanta"
PART_NUMBER"CS00002JB13";
"B"
$PN"2"48;
"A"
$PN"1"18;
%"GND"
"1","(-1125,13975)","0","pure_quanta_power","I21";
;
SIZE"1B"
CDS_LIB"pure_quanta_power"
HDL_POWER"GND";
"A<SIZE-1..0>\NAC"4;
%"MOSFET_NCH_DUAL"
"1","(-1175,14325)","0","pure_quanta","I22";
;
LOCATION"Q125"
$SEC"1"
CDS_SEC"1"
MATERIAL"IC"
PART_TYPE"SMLF"
VALUE"PJT138K"
ROOM"SCM_P12V_MAM_BOM1"
CDS_LIB"pure_quanta"
CDS_LMAN_SYM_OUTLINE"-150,150,150,-150"
NEEDS_NO_SIZE"TRUE"
PART_NUMBER"BAM138K0003";
"D1"
$PN"6"49;
"G1"
$PN"2"48;
"S1"
$PN"1"4;
%"GND"
"1","(-450,14350)","0","pure_quanta_power","I23";
;
CDS_LIB"pure_quanta_power"
SIZE"1B"
HDL_POWER"GND";
"A<SIZE-1..0>\NAC"5;
%"MOSFET_NCH_DUAL"
"2","(-500,14675)","0","pure_quanta","I24";
;
LOCATION"Q125"
$SEC"2"
CDS_SEC"2"
ROOM"SCM_P12V_MAM_BOM1"
VALUE"PJT138K"
PART_TYPE"SMLF"
MATERIAL"IC"
NEEDS_NO_SIZE"TRUE"
CDS_LMAN_SYM_OUTLINE"-150,150,150,-150"
CDS_LIB"pure_quanta"
PART_NUMBER"BAM138K0003";
"S2"
$PN"4"5;
"G2"
$PN"5"49;
"D2"
$PN"3"55;
%"Q_RES"
"2","(-1125,14925)","0","pure_quanta","I25";
;
LOCATION"R4071"
$SEC"1"
CDS_SEC"1"
WATTAGE"1/16W"
VALUE"10K"
MATERIAL"CHIP"
TOLERANCE"1%"
PACK_TYPE"0402LF"
ROOM"SCM_P12V_MAM_BOM1"
CDS_LIB"pure_quanta"
PART_NUMBER"CS31002FB08";
"A"
$PN"1"6;
"B"
$PN"2"49;
%"UNIVERSAL_POWER"
"1","(-1125,15175)","0","pure_quanta_power","I26";
;
HDL_POWER"P12V_AUX"
CDS_LIB"pure_quanta_power";
"A"6;
%"Q_RES"
"1","(100,15000)","0","pure_quanta","I27";
;
LOCATION"R3997"
$SEC"1"
CDS_SEC"1"
WATTAGE"1/16W"
TOLERANCE"5%"
PACK_TYPE"0402LF"
MATERIAL"CHIP"
VALUE"0"
ROOM"SCM_P12V_MAM_BOM1"
CDS_LIB"pure_quanta"
PART_NUMBER"CS00002JB13";
"B"
$PN"2"50;
"A"
$PN"1"55;
%"DIODE_TVS"
"1","(-50,15650)","1","pure_quanta","I28";
;
LOCATION"PD115"
$SEC"1"
CDS_SEC"1"
VALUE"SMF14A"
MATERIAL"IC"
PART_TYPE"SMLF"
CDS_LMAN_SYM_OUTLINE"-100,50,100,-50"
CDS_LIB"pure_quanta"
PIN_NAMES_ROTATE"TRUE"
PART_NUMBER"BCSMF14AZ01";
"C"
$PN"C"
Pin_Length"SHORT"42;
"A"
$PN"A"43;
%"GND"
"1","(100,15250)","0","pure_quanta_power","I29";
;
CDS_LIB"pure_quanta_power"
SIZE"1B"
HDL_POWER"GND";
"A<SIZE-1..0>\NAC"43;
%"Q_RES"
"1","(-1800,13175)","0","pure_quanta","I3";
;
LOCATION"R1856"
$SEC"1"
CDS_SEC"1"
TOLERANCE"1%"
VALUE"100"
PACK_TYPE"0402LF"
MATERIAL"CHIP"
WATTAGE"1/16W"
CDS_LIB"pure_quanta"
PART_NUMBER"CS11002FB07";
"B"
$PN"2"47;
"A"
$PN"1"62;
%"UNIVERSAL_POWER"
"1","(100,15975)","0","pure_quanta_power","I30";
;
HDL_POWER"P12V_AUX"
CDS_LIB"pure_quanta_power";
"A"42;
%"Q_CAP"
"1","(325,15625)","0","pure_quanta","I31";
;
LOCATION"PC2230"
$SEC"1"
CDS_SEC"1"
MATERIAL"X6S"
VALUE"1UF"
VOLTAGE"25V"
PACK_TYPE"C0402"
TOLERANCE"10%"
CDS_LIB"pure_quanta"
PART_NUMBER"CH5104KEB02";
"B"
$PN"2"43;
"A"
$PN"1"42;
%"GND"
"1","(825,11250)","0","pure_quanta_power","I32";
;
SIZE"1B"
CDS_LIB"pure_quanta_power"
HDL_POWER"GND";
"A<SIZE-1..0>\NAC"7;
%"Q_CAP"
"1","(825,11475)","0","pure_quanta","I33";
;
LOCATION"PC2232"
$SEC"1"
CDS_SEC"1"
ROOM"SCM_P12V_MPS_BOM2"
VOLTAGE"25V"
MATERIAL"X7R"
PACK_TYPE"C0402"
VALUE"0.047UF"
CDS_LIB"pure_quanta"
TOLERANCE"10%"
PART_NUMBER"CH3474K1B04";
"B"
$PN"2"7;
"A"
$PN"1"30;
%"GND"
"1","(1166,11416)","0","pure_quanta_power","I34";
;
CDS_LIB"pure_quanta_power"
SIZE"1B"
HDL_POWER"GND";
"A<SIZE-1..0>\NAC"31;
%"Q_RES"
"2","(2250,11275)","0","pure_quanta","I35";
;
LOCATION"PR4005"
$SEC"1"
CDS_SEC"1"
WATTAGE"1/16W"
TOLERANCE"1%"
PACK_TYPE"0402LF"
ROOM"SCM_P12V_MPS_BOM2"
MATERIAL"CHIP"
VALUE"30.1K"
CDS_LIB"pure_quanta"
PART_NUMBER"CS33012FB03";
"A"
$PN"1"25;
"B"
$PN"2"41;
%"GND"
"1","(750,12325)","0","pure_quanta_power","I36";
;
SIZE"1B"
CDS_LIB"pure_quanta_power"
HDL_POWER"GND";
"A<SIZE-1..0>\NAC"8;
%"Q_CAP"
"1","(750,12550)","0","pure_quanta","I37";
;
LOCATION"PC2231"
$SEC"1"
CDS_SEC"1"
VOLTAGE"25V"
ROOM"SCM_P12V_MPS_BOM2"
VALUE"1UF"
MATERIAL"X6S"
PACK_TYPE"C0402"
CDS_LIB"pure_quanta"
TOLERANCE"10%"
PART_NUMBER"CH5104KEB02";
"B"
$PN"2"8;
"A"
$PN"1"20;
%"UNIVERSAL_POWER"
"1","(750,12900)","0","pure_quanta_power","I39";
;
HDL_POWER"P12V_AUX"
CDS_LIB"pure_quanta_power";
"A"20;
%"GND"
"1","(-525,11350)","0","pure_quanta_power","I4";
;
SIZE"1B"
CDS_LIB"pure_quanta_power"
HDL_POWER"GND";
"A<SIZE-1..0>\NAC"9;
%"Q_RES"
"1","(3150,11650)","0","pure_quanta","I40";
;
LOCATION"PR4007"
$SEC"1"
CDS_SEC"1"
VALUE"10K"
TOLERANCE"1%"
MATERIAL"CHIP"
PACK_TYPE"0402LF"
WATTAGE"1/16W"
ROOM"SCM_P12V_MPS_BOM2"
CDS_LIB"pure_quanta"
PART_NUMBER"CS31002FB08";
"B"
$PN"2"11;
"A"
$PN"1"24;
%"Q_RES"
"2","(2625,12125)","0","pure_quanta","I41";
;
LOCATION"PR4006"
$SEC"1"
CDS_SEC"1"
VALUE"100"
ROOM"SCM_P12V_MPS_BOM2"
TOLERANCE"1%"
MATERIAL"EMPTY"
PACK_TYPE"0402LF"
WATTAGE"1/16W"
CDS_LIB"pure_quanta"
PART_NUMBER"CS11002FB07";
"A"
$PN"1"19;
"B"
$PN"2"21;
%"VCCAUX15"
"1","(2875,12950)","0","pure_quanta_power","I42";
;
HDL_POWER"P3V3_AUX"
CDS_LIB"pure_quanta_power";
"A"10;
%"Q_RES"
"2","(2875,12775)","0","pure_quanta","I43";
;
LOCATION"R3836"
$SEC"1"
CDS_SEC"1"
MATERIAL"CHIP"
WATTAGE"1/16W"
VALUE"10K"
ROOM"SCM_P12V_MPS_BOM2"
TOLERANCE"1%"
PACK_TYPE"0402LF"
CDS_LIB"pure_quanta"
PART_NUMBER"CS31002FB08";
"A"
$PN"1"10;
"B"
$PN"2"23;
%"GND"
"1","(2600,10875)","0","pure_quanta_power","I44";
;
SIZE"1B"
CDS_LIB"pure_quanta_power"
HDL_POWER"GND";
"A<SIZE-1..0>\NAC"41;
%"Q_CAP"
"1","(2600,11300)","0","pure_quanta","I45";
;
LOCATION"PC2235"
$SEC"1"
CDS_SEC"1"
MATERIAL"X7R"
PACK_TYPE"C0402"
VOLTAGE"50V"
ROOM"SCM_P12V_MPS_BOM2"
VALUE"100NF"
CDS_LIB"pure_quanta"
TOLERANCE"10%"
PART_NUMBER"CH4106K1B01";
"B"
$PN"2"41;
"A"
$PN"1"25;
%"GND"
"1","(3825,11300)","0","pure_quanta_power","I46";
;
CDS_LIB"pure_quanta_power"
SIZE"1B"
HDL_POWER"GND";
"A<SIZE-1..0>\NAC"34;
%"VCCAUX15"
"1","(3475,11725)","0","pure_quanta_power","I48";
;
HDL_POWER"P3V3_AUX"
CDS_LIB"pure_quanta_power";
"A"11;
%"Q_RES"
"2","(3625,11625)","0","pure_quanta","I49";
;
LOCATION"PR4011"
$SEC"1"
CDS_SEC"1"
PACK_TYPE"0402LF"
MATERIAL"CHIP"
TOLERANCE"1%"
ROOM"SCM_P12V_MPS_BOM2"
VALUE"10K"
WATTAGE"1/16W"
CDS_LIB"pure_quanta"
PART_NUMBER"CS31002FB08";
"A"
$PN"1"22;
"B"
$PN"2"34;
%"GND"
"1","(-75,11275)","0","pure_quanta_power","I5";
;
CDS_LIB"pure_quanta_power"
SIZE"1B"
HDL_POWER"GND";
"A<SIZE-1..0>\NAC"12;
%"Q_RES"
"2","(3225,12125)","0","pure_quanta","I50";
;
LOCATION"PR4009"
$SEC"1"
CDS_SEC"1"
PACK_TYPE"0402LF"
TOLERANCE"1%"
MATERIAL"EMPTY"
VALUE"71.5K"
ROOM"SCM_P12V_MPS_BOM2"
WATTAGE"1/16W"
CDS_LIB"pure_quanta"
PART_NUMBER"CS37152FB05";
"A"
$PN"1"19;
"B"
$PN"2"22;
%"Q_RES"
"2","(3625,12050)","0","pure_quanta","I51";
;
LOCATION"PR4010"
$SEC"1"
CDS_SEC"1"
ROOM"SCM_P12V_MPS_BOM2"
PACK_TYPE"0402LF"
MATERIAL"CHIP"
WATTAGE"1/16W"
TOLERANCE"1%"
VALUE"120K"
CDS_LIB"pure_quanta"
PART_NUMBER"CS41202FB05";
"A"
$PN"1"35;
"B"
$PN"2"22;
%"Q_CAP"
"1","(4150,11625)","0","pure_quanta","I52";
;
LOCATION"PC2239"
$SEC"1"
CDS_SEC"1"
TOLERANCE"20%"
MATERIAL"X7R"
VOLTAGE"16V"
VALUE"2.2UF"
ROOM"SCM_P12V_MPS_BOM2"
PACK_TYPE"C0603"
CDS_LIB"pure_quanta"
PART_NUMBER"CH5223M1900";
"B"
$PN"2"34;
"A"
$PN"1"36;
%"Q_RES"
"2","(4150,12050)","0","pure_quanta","I53";
;
LOCATION"PR4014"
$SEC"1"
CDS_SEC"1"
PACK_TYPE"0603LF"
WATTAGE"1/10W"
ROOM"SCM_P12V_MPS_BOM2"
VALUE"49.9"
MATERIAL"CHIP"
TOLERANCE"1%"
CDS_LIB"pure_quanta"
PART_NUMBER"CS04993F909";
"A"
$PN"1"35;
"B"
$PN"2"36;
%"UNIVERSAL_POWER"
"1","(4150,12350)","0","pure_quanta_power","I54";
;
HDL_POWER"P12V_AUX"
CDS_LIB"pure_quanta_power";
"A"35;
%"GND"
"1","(4500,12200)","0","pure_quanta_power","I55";
;
CDS_LIB"pure_quanta_power"
SIZE"1B"
HDL_POWER"GND";
"A<SIZE-1..0>\NAC"13;
%"Q_CAP"
"1","(4500,12475)","2","pure_quanta","I56";
;
LOCATION"PC2241"
$SEC"1"
CDS_SEC"1"
VOLTAGE"25V"
TOLERANCE"10%"
MATERIAL"X7R"
VALUE"0.1UF"
PACK_TYPE"0402"
ROOM"SCM_P12V_MPS_BOM2"
CDS_LIB"pure_quanta"
PART_NUMBER"CH4104K1B00";
"B"
$PN"2"13;
"A"
$PN"1"19;
%"UNIVERSAL_POWER"
"1","(4500,12750)","2","pure_quanta_power","I57";
;
HDL_POWER"P12V_SCM_R"
CDS_LIB"pure_quanta_power";
"A"19;
%"GND"
"1","(675,14150)","0","pure_quanta_power","I59";
;
SIZE"1B"
CDS_LIB"pure_quanta_power"
HDL_POWER"GND";
"A<SIZE-1..0>\NAC"14;
%"Q_CAP"
"1","(350,11250)","0","pure_quanta","I6";
;
LOCATION"PC2340"
$SEC"1"
CDS_SEC"1"
PACK_TYPE"C0402"
VALUE"560PF"
VOLTAGE"50V"
MATERIAL"X7R"
ROOM"SCM_P12V_MPS_BOM2"
CDS_LIB"pure_quanta"
TOLERANCE"10%"
PART_NUMBER"CH1566K1B09";
"B"
$PN"2"16;
"A"
$PN"1"46;
%"Q_RES"
"2","(675,14375)","0","pure_quanta","I60";
;
LOCATION"PR4002"
$SEC"1"
CDS_SEC"1"
ROOM"SCM_P12V_MAM_BOM1"
TOLERANCE"1%"
VALUE"15K"
MATERIAL"CHIP"
PACK_TYPE"0402LF"
WATTAGE"1/16W"
CDS_LIB"pure_quanta"
PART_NUMBER"CS31502FB05";
"A"
$PN"1"33;
"B"
$PN"2"14;
%"GND"
"1","(1525,14150)","0","pure_quanta_power","I61";
;
CDS_LIB"pure_quanta_power"
SIZE"1B"
HDL_POWER"GND";
"A<SIZE-1..0>\NAC"32;
%"Q_RES"
"2","(1525,14375)","0","pure_quanta","I62";
;
LOCATION"PR4004"
$SEC"1"
CDS_SEC"1"
ROOM"SCM_P12V_MAM_BOM1"
TOLERANCE"1%"
MATERIAL"CHIP"
VALUE"17.8K"
PACK_TYPE"0402LF"
WATTAGE"1/16W"
CDS_LIB"pure_quanta"
PART_NUMBER"CS31782FB04";
"A"
$PN"1"57;
"B"
$PN"2"32;
%"Q_RES"
"2","(675,14650)","0","pure_quanta","I63";
;
LOCATION"PR4001"
$SEC"1"
CDS_SEC"1"
WATTAGE"1/16W"
MATERIAL"CHIP"
TOLERANCE"1%"
VALUE"6.8K"
PACK_TYPE"0402LF"
ROOM"SCM_P12V_MAM_BOM1"
CDS_LIB"pure_quanta"
PART_NUMBER"CS26802FB02";
"A"
$PN"1"50;
"B"
$PN"2"33;
%"GND"
"1","(1000,14825)","0","pure_quanta_power","I64";
;
CDS_LIB"pure_quanta_power"
SIZE"1B"
HDL_POWER"GND";
"A<SIZE-1..0>\NAC"15;
%"Q_RES"
"2","(675,15325)","0","pure_quanta","I65";
;
LOCATION"PR4000"
$SEC"1"
CDS_SEC"1"
PACK_TYPE"0402LF"
MATERIAL"CHIP"
TOLERANCE"1%"
VALUE"160K"
ROOM"SCM_P12V_MAM_BOM1"
WATTAGE"1/16W"
CDS_LIB"pure_quanta"
PART_NUMBER"CS41602FB05";
"A"
$PN"1"42;
"B"
$PN"2"50;
%"Q_CAP"
"1","(1000,15200)","0","pure_quanta","I66";
;
LOCATION"PC2233"
$SEC"1"
CDS_SEC"1"
ROOM"SCM_P12V_MAM_BOM1"
MATERIAL"X6S"
VALUE"1UF"
VOLTAGE"25V"
PACK_TYPE"C0402"
TOLERANCE"10%"
CDS_LIB"pure_quanta"
PART_NUMBER"CH5104KEB02";
"B"
$PN"2"15;
"A"
$PN"1"56;
%"Q_CAP"
"1","(1225,14900)","1","pure_quanta","I67";
;
LOCATION"PC2234"
$SEC"1"
CDS_SEC"1"
VOLTAGE"25V"
VALUE"1UF"
PACK_TYPE"C0402"
ROOM"SCM_P12V_MAM_BOM1"
CDS_LIB"pure_quanta"
MATERIAL"X6S"
TOLERANCE"10%"
PART_NUMBER"CH5104KEB02";
"B"
$PN"2"51;
"A"
$PN"1"15;
%"Q_RES"
"2","(1000,15625)","0","pure_quanta","I68";
;
LOCATION"PR4003"
$SEC"1"
CDS_SEC"1"
PACK_TYPE"0402LF"
ROOM"SCM_P12V_MAM_BOM1"
VALUE"10"
TOLERANCE"1%"
WATTAGE"1/16W"
MATERIAL"CHIP"
CDS_LIB"pure_quanta"
PART_NUMBER"CS01002FB07";
"A"
$PN"1"42;
"B"
$PN"2"56;
%"GND"
"1","(3000,14150)","0","pure_quanta_power","I69";
;
SIZE"1B"
CDS_LIB"pure_quanta_power"
HDL_POWER"GND";
"A<SIZE-1..0>\NAC"40;
%"GND"
"1","(350,11025)","0","pure_quanta_power","I7";
;
CDS_LIB"pure_quanta_power"
SIZE"1B"
HDL_POWER"GND";
"A<SIZE-1..0>\NAC"16;
%"Q_RES"
"2","(3125,14525)","0","pure_quanta","I70";
;
LOCATION"PR4008"
$SEC"1"
CDS_SEC"1"
WATTAGE"1/16W"
VALUE"1.33K"
TOLERANCE"1%"
MATERIAL"CHIP"
PACK_TYPE"0402LF"
ROOM"SCM_P12V_MAM_BOM1"
CDS_LIB"pure_quanta"
PART_NUMBER"CS21332FB05";
"A"
$PN"1"59;
"B"
$PN"2"40;
%"Q_CAP"
"1","(3075,15225)","0","pure_quanta","I71";
;
LOCATION"PC2236"
$SEC"1"
CDS_SEC"1"
VOLTAGE"50V"
ROOM"SCM_P12V_MAM_BOM1"
VALUE"0.01UF"
PACK_TYPE"C0402"
MATERIAL"EMPTY"
TOLERANCE"10%"
CDS_LIB"pure_quanta"
PART_NUMBER"CH31006KB18";
"B"
$PN"2"53;
"A"
$PN"1"37;
%"Q_CAP"
"1","(3675,15000)","1","pure_quanta","I72";
;
LOCATION"PC2237"
$SEC"1"
CDS_SEC"1"
VOLTAGE"50V"
VALUE"3900PF"
PACK_TYPE"C0402"
ROOM"SCM_P12V_MAM_BOM1"
CDS_LIB"pure_quanta"
MATERIAL"X7R"
TOLERANCE"10%"
PART_NUMBER"CH23906KB14";
"B"
$PN"2"17;
"A"
$PN"1"53;
%"Q_RES"
"1","(3750,14900)","0","pure_quanta","I73";
;
LOCATION"PR4012"
$SEC"1"
CDS_SEC"1"
PACK_TYPE"0402LF"
VALUE"0"
MATERIAL"CHIP"
TOLERANCE"5%"
ROOM"SCM_P12V_MAM_BOM1"
WATTAGE"1/16W"
CDS_LIB"pure_quanta"
PART_NUMBER"CS00002JB13";
"B"
$PN"2"45;
"A"
$PN"1"52;
%"Q_RES"
"2","(3400,15250)","0","pure_quanta","I74";
;
LOCATION"PR4526"
$SEC"1"
CDS_SEC"1"
PACK_TYPE"0402LF"
MATERIAL"CHIP"
WATTAGE"1/16W"
ROOM"SCM_P12V_MAM_BOM1"
VALUE"10M"
TOLERANCE"1%"
CDS_LIB"pure_quanta"
PART_NUMBER"CS61002FB02";
"A"
$PN"1"37;
"B"
$PN"2"53;
%"GND"
"1","(4050,14950)","0","pure_quanta_power","I75";
;
CDS_LIB"pure_quanta_power"
SIZE"1B"
HDL_POWER"GND";
"A<SIZE-1..0>\NAC"17;
%"Q_RES"
"2","(4100,15150)","0","pure_quanta","I76";
;
LOCATION"R4013"
$SEC"1"
CDS_SEC"1"
ROOM"SCM_P12V_MAM_BOM1"
VALUE"100K"
TOLERANCE"1%"
PACK_TYPE"0402LF"
MATERIAL"CHIP"
WATTAGE"1/16W"
CDS_LIB"pure_quanta"
PART_NUMBER"CS41002FB09";
"A"
$PN"1"39;
"B"
$PN"2"58;
%"VCCAUX15"
"1","(4300,15500)","0","pure_quanta_power","I77";
;
HDL_POWER"P3V3_AUX"
CDS_LIB"pure_quanta_power";
"A"39;
%"Q_RES"
"2","(4525,15150)","0","pure_quanta","I78";
;
LOCATION"R4015"
$SEC"1"
CDS_SEC"1"
PACK_TYPE"0402LF"
WATTAGE"1/16W"
MATERIAL"CHIP"
VALUE"100K"
TOLERANCE"1%"
ROOM"SCM_P12V_MAM_BOM1"
CDS_LIB"pure_quanta"
PART_NUMBER"CS41002FB09";
"A"
$PN"1"39;
"B"
$PN"2"45;
%"SCHOTTKY_AC"
"1","(3500,15850)","1","pure_quanta","I79";
;
LOCATION"PD116"
$SEC"1"
CDS_SEC"1"
MATERIAL"IC"
VALUE"B340A-13-F"
PART_TYPE"SMLF"
NEEDS_NO_SIZE"TRUE"
CDS_LMAN_SYM_OUTLINE"-75,50,75,-50"
CDS_LIB"pure_quanta"
PART_NUMBER"BC000340Z30";
"C"
$PN"C"37;
"A"
$PN"A"38;
%"Q_CAP"
"1","(-525,11650)","0","pure_quanta","I8";
;
LOCATION"PC2229"
$SEC"1"
CDS_SEC"1"
PACK_TYPE"0402"
VOLTAGE"16V"
MATERIAL"X7R"
ROOM"SCM_P12V_MPS_BOM2"
VALUE"0.22UF"
CDS_LIB"pure_quanta"
TOLERANCE"10%"
PART_NUMBER"CH4223K1B00";
"B"
$PN"2"9;
"A"
$PN"1"28;
%"Q_CAP"
"1","(3975,15825)","0","pure_quanta","I80";
;
LOCATION"PC2238"
$SEC"1"
CDS_SEC"1"
VOLTAGE"25V"
VALUE"0.1UF"
PACK_TYPE"0402"
MATERIAL"X7R"
TOLERANCE"10%"
CDS_LIB"pure_quanta"
PART_NUMBER"CH4104K1B00";
"B"
$PN"2"38;
"A"
$PN"1"37;
%"Q_CAP"
"1","(4400,15825)","0","pure_quanta","I81";
;
LOCATION"PC2240"
$SEC"1"
CDS_SEC"1"
MATERIAL"X6S"
VOLTAGE"16V"
PACK_TYPE"C0805"
VALUE"10UF"
TOLERANCE"10%"
CDS_LIB"pure_quanta"
PART_NUMBER"CH6103KEA01";
"B"
$PN"2"38;
"A"
$PN"1"37;
%"GND"
"1","(4800,15525)","0","pure_quanta_power","I83";
;
CDS_LIB"pure_quanta_power"
SIZE"1B"
HDL_POWER"GND";
"A<SIZE-1..0>\NAC"38;
%"Q_CAP"
"1","(4800,15825)","0","pure_quanta","I84";
;
LOCATION"PC2242"
$SEC"1"
CDS_SEC"1"
VOLTAGE"16V"
VALUE"22UF"
MATERIAL"X6S"
PACK_TYPE"C0805"
CDS_LIB"pure_quanta"
TOLERANCE"20%"
PART_NUMBER"CH6223MEA01";
"B"
$PN"2"38;
"A"
$PN"1"37;
%"UNIVERSAL_POWER"
"1","(4800,16125)","2","pure_quanta_power","I85";
;
HDL_POWER"P12V_SCM_R"
CDS_LIB"pure_quanta_power";
"A"37;
%"MAX15090BEWIT"
"1","(2275,14900)","0","pure_quanta","I86";
;
LOCATION"PU300"
$SEC"1"
CDS_SEC"1"
ROOM"SCM_P12V_MAM_BOM1"
PART_TYPE"SMLF"
VALUE"MAX15090BEWI+T"
MATERIAL"IC"
CDS_LMAN_SYM_OUTLINE"-250,550,250,-550"
CDS_LIB"pure_quanta"
PIN_NAMES_ROTATE"TRUE"
PART_NUMBER"AL015080B00";
"PG"
$PN"D7"52;
"FAULT# \B"
$PN"C7"54;
"GND_C2"
$PN"C2"40;
"GND_C1"
$PN"C1"40;
"GND_B2"
$PN"B2"40;
"CDLY"
$PN"A7"40;
"GATE"
$PN"A6"53;
"OUT_D6"
$PN"D6"37;
"OUT_D4"
$PN"D4"37;
"OUT_C6"
$PN"C6"37;
"OUT_C4"
$PN"C4"37;
"OUT_B6"
$PN"B6"37;
"OUT_B4"
$PN"B4"37;
"OUT_A4"
$PN"A4"37;
"ISENSE"
$PN"A1"59;
"OV"
$PN"D3"33;
"UV"
$PN"D2"50;
"REG"
$PN"D1"51;
"EN# \B"
$PN"B7"32;
"CB"
$PN"B1"57;
"IN_D5"
$PN"D5"42;
"IN_C5"
$PN"C5"42;
"IN_C3"
$PN"C3"42;
"IN_B5"
$PN"B5"42;
"IN_B3"
$PN"B3"42;
"IN_A5"
$PN"A5"42;
"IN_A3"
$PN"A3"42;
"VCC"
$PN"A2"56;
%"Q_RES"
"1","(3175,12500)","0","pure_quanta","I89";
;
LOCATION"R8012"
SEC"1"
PACK_TYPE"0402LF"
MATERIAL"CHIP"
VALUE"0"
TOLERANCE"5%"
ROOM"SCM_P12V_MPS_BOM2"
WATTAGE"1/16W"
SEC_TYPE"0402LF"
CDS_LIB"pure_quanta"
PART_NUMBER"CS00002JB13";
"B"
$PN"2"44;
"A"
$PN"1"23;
%"MOSFET_NCH_GDS_ESD_PROTECTED"
"1","(-775,13175)","0","pure_quanta","I9";
;
LOCATION"Q39"
$SEC"1"
CDS_SEC"1"
MATERIAL"IC"
VALUE"2N7002K"
PART_TYPE"SMLF"
NEEDS_NO_SIZE"TRUE"
CDS_LIB"pure_quanta"
CDS_LMAN_SYM_OUTLINE"-125,150,125,-150"
PART_NUMBER"BAM70020002";
"S"
$PN"S"1;
"G"
$PN"G"47;
"D"
$PN"D"18;
%"Q_RES"
"1","(3750,14800)","0","pure_quanta","I91";
;
LOCATION"R8030"
$SEC"1"
CDS_SEC"1"
ROOM"SCM_P12V_MAM_BOM1"
PACK_TYPE"0402LF"
TOLERANCE"5%"
VALUE"0"
MATERIAL"CHIP"
WATTAGE"1/16W"
CDS_LIB"pure_quanta"
PART_NUMBER"CS00002JB13";
"B"
$PN"2"58;
"A"
$PN"1"54;
%"Q_RES"
"1","(3450,11100)","0","pure_quanta","I93";
;
LOCATION"R8031"
$SEC"1"
CDS_SEC"1"
WATTAGE"1/16W"
PACK_TYPE"0402LF"
TOLERANCE"5%"
MATERIAL"CHIP"
VALUE"0"
ROOM"SCM_P12V_MPS_BOM2"
CDS_LIB"pure_quanta"
PART_NUMBER"CS00002JB13";
"B"
$PN"2"61;
"A"
$PN"1"24;
%"RS31312R"
"1","(1625,12025)","0","pure_quanta","I95";
;
LOCATION"PU299"
SEC"1"
PART_TYPE"SMLF"
VALUE"RS31312R"
MATERIAL"IC"
ROOM"SCM_P12V_MPS_BOM2"
CDS_LIB"pure_quanta"
NEEDS_NO_SIZE"TRUE"
CDS_LMAN_SYM_OUTLINE"-250,525,250,-525"
SEC_TYPE""
PART_NUMBER"AL031312000";
"GND"
$PN"7"31;
"SS"
$PN"6"30;
"ISET"
$PN"5"29;
"TIMER"
$PN"4"28;
"ENTM"
$PN"3"27;
"LOADEN"
$PN"2"27;
"EN"
$PN"1"26;
"VIN_26"
$PN"26"20;
"VIN_25"
$PN"25"20;
"VIN_24"
$PN"24"20;
"VIN_23"
$PN"23"20;
"IMON"
$PN"8"25;
"FLTB"
$PN"9"24;
"PG"
$PN"10"23;
"OV"
$PN"11"22;
"VOUT_13"
$PN"13"19;
"AVIN"
$PN"12"21;
"VOUT_14"
$PN"14"19;
"VOUT_15"
$PN"15"19;
"VOUT_16"
$PN"16"19;
"VOUT_17"
$PN"17"19;
"VOUT_18"
$PN"18"19;
"VOUT_19"
$PN"19"19;
"VIN_21_22"
$PN"21_22"20;
"VOUT_20"
$PN"20"19;
END.
